# S9S_MB_2U (Grand Teton) — schematic netlist excerpt (pin names and nets, part order shuffled) for the footprints in the layout excerpt that follows; sources: Cadence DE-HDL packaged netlist, KiCad conversion of 03242023_DA0F0TMBIJ0_F0T_Motherboard_J_brd_V01_OCP.brd

C408  Q_CAP  22UF 4V 20% X6S  pkg C0402  page 74 : A = PVCCINFAON_CPU0 ; B = GND
R3867  Q_RES  0 5% EMPTY  pkg 0402LF  page 162 : A = P12V_OCP_SENSE_2 ; B = P12V_OCP_V3_2_ISENSE_MAM_MAM

(kicad_pcb
	(version 20260206)
	(generator "pcbnew")
	(generator_version "10.0")
	(general
		(thickness 1.6)
		(legacy_teardrops no)
	)
	(paper "A4")
	(title_block
		(title "03242023_DA0F0TMBIJ0_F0T_Motherboard_J_brd_V01_OCP.brd")
		(comment 1 "Grand Teton / footprints 139-140 of 6105")
	)
	(layers
		(0 "F.Cu" signal "TOP")
		(4 "In1.Cu" signal "GND")
		(6 "In2.Cu" signal "IN1")
		(8 "In3.Cu" signal "GND1")
		(10 "In4.Cu" signal "IN2")
		(12 "In5.Cu" signal "GND2")
		(14 "In6.Cu" signal "IN3")
		(16 "In7.Cu" signal "GND3")
		(18 "In8.Cu" signal "VCC")
		(20 "In9.Cu" signal "VCC1")
		(22 "In10.Cu" signal "GND4")
		(24 "In11.Cu" signal "IN4")
		(26 "In12.Cu" signal "GND5")
		(28 "In13.Cu" signal "IN5")
		(30 "In14.Cu" signal "GND6")
		(32 "In15.Cu" signal "IN6")
		(34 "In16.Cu" signal "GND7")
		(2 "B.Cu" signal "BOTTOM")
		(9 "F.Adhes" user "F.Adhesive")
		(11 "B.Adhes" user "B.Adhesive")
		(13 "F.Paste" user "Package Geometry/Pastemask Top")
		(15 "B.Paste" user "Package Geometry/Pastemask Bottom")
		(5 "F.SilkS" user "Ref Des/Silkscreen Top")
		(7 "B.SilkS" user "Ref Des/Silkscreen Bottom")
		(1 "F.Mask" user "Board Geometry/Soldermask Top")
		(3 "B.Mask" user "Board Geometry/Soldermask Bottom")
		(17 "Dwgs.User" user "User.Drawings")
		(19 "Cmts.User" user "User.Comments")
		(21 "Eco1.User" user "User.Eco1")
		(23 "Eco2.User" user "User.Eco2")
		(25 "Edge.Cuts" user "Board Geometry/Outline")
		(27 "Margin" user)
		(31 "F.CrtYd" user "Package Geometry/Place Bound Top")
		(29 "B.CrtYd" user "Package Geometry/Place Bound Bottom")
		(35 "F.Fab" user "Ref Des/Assembly Top")
		(33 "B.Fab" user "Ref Des/Assembly Bottom")
	)
	(footprint ""
		(layer "F.Cu")
		(at 367.44783 -238.162338 90)
		(property "Reference" "C408"
			(at 0 0 90)
			(layer "F.SilkS")
			(hide yes)
			(effects
				(font
					(size 1.27 1.27)
				)
			)
		)
		(property "Value" ""
			(at 0 0 90)
			(layer "F.Fab")
			(effects
				(font
					(size 1.27 1.27)
				)
			)
		)
		(duplicate_pad_numbers_are_jumpers no)
		(fp_line
			(start 0.7874 -0.4064)
			(end 0.7874 0.4064)
			(stroke
				(width 0.1524)
				(type default)
			)
			(layer "F.SilkS")
		)
		(fp_line
			(start -0.7874 -0.4064)
			(end 0.7874 -0.4064)
			(stroke
				(width 0.1524)
				(type default)
			)
			(layer "F.SilkS")
		)
		(fp_line
			(start 0.7874 0.4064)
			(end -0.7874 0.4064)
			(stroke
				(width 0.1524)
				(type default)
			)
			(layer "F.SilkS")
		)
		(fp_line
			(start -0.7874 0.4064)
			(end -0.7874 -0.4064)
			(stroke
				(width 0.1524)
				(type default)
			)
			(layer "F.SilkS")
		)
		(fp_line
			(start -0.12065 -0.305054)
			(end -0.12065 -0.2794)
			(stroke
				(width 0.1)
				(type default)
			)
			(layer "F.Fab")
		)
		(fp_line
			(start -0.67945 -0.305054)
			(end -0.12065 -0.305054)
			(stroke
				(width 0.1)
				(type default)
			)
			(layer "F.Fab")
		)
		(fp_line
			(start 0.67945 -0.3048)
			(end 0.67945 0.3048)
			(stroke
				(width 0.1)
				(type default)
			)
			(layer "F.Fab")
		)
		(fp_line
			(start 0.12065 -0.3048)
			(end 0.67945 -0.3048)
			(stroke
				(width 0.1)
				(type default)
			)
			(layer "F.Fab")
		)
		(fp_line
			(start 0.12065 -0.2794)
			(end 0.12065 -0.3048)
			(stroke
				(width 0.1)
				(type default)
			)
			(layer "F.Fab")
		)
		(fp_line
			(start -0.12065 -0.2794)
			(end 0.12065 -0.2794)
			(stroke
				(width 0.1)
				(type default)
			)
			(layer "F.Fab")
		)
		(fp_line
			(start 0.120396 0.2794)
			(end -0.12065 0.2794)
			(stroke
				(width 0.1)
				(type default)
			)
			(layer "F.Fab")
		)
		(fp_line
			(start -0.12065 0.2794)
			(end -0.12065 0.3048)
			(stroke
				(width 0.1)
				(type default)
			)
			(layer "F.Fab")
		)
		(fp_line
			(start 0.67945 0.3048)
			(end 0.120396 0.3048)
			(stroke
				(width 0.1)
				(type default)
			)
			(layer "F.Fab")
		)
		(fp_line
			(start 0.120396 0.3048)
			(end 0.120396 0.2794)
			(stroke
				(width 0.1)
				(type default)
			)
			(layer "F.Fab")
		)
		(fp_line
			(start -0.12065 0.3048)
			(end -0.67945 0.3048)
			(stroke
				(width 0.1)
				(type default)
			)
			(layer "F.Fab")
		)
		(fp_line
			(start -0.67945 0.3048)
			(end -0.67945 -0.305054)
			(stroke
				(width 0.1)
				(type default)
			)
			(layer "F.Fab")
		)
		(pad "1" smd circle
			(at -0.40005 0 90)
			(size 0 0)
			(layers "F.Cu" "F.Mask" "F.Paste")
			(net "PVCCINFAON_CPU0")
		)
		(pad "2" smd circle
			(at 0.40005 0 90)
			(size 0 0)
			(layers "F.Cu" "F.Mask" "F.Paste")
			(net "GND")
		)
	)
	(footprint ""
		(layer "F.Cu")
		(at 60.527438 -31.887922 -90)
		(property "Reference" "R3867"
			(at 0 0 270)
			(layer "F.SilkS")
			(hide yes)
			(effects
				(font
					(size 1.27 1.27)
				)
			)
		)
		(property "Value" ""
			(at 0 0 270)
			(layer "F.Fab")
			(effects
				(font
					(size 1.27 1.27)
				)
			)
		)
		(duplicate_pad_numbers_are_jumpers no)
		(fp_line
			(start -0.7874 0.4064)
			(end -0.7874 -0.4064)
			(stroke
				(width 0.1524)
				(type default)
			)
			(layer "F.SilkS")
		)
		(fp_line
			(start 0.7874 0.4064)
			(end -0.7874 0.4064)
			(stroke
				(width 0.1524)
				(type default)
			)
			(layer "F.SilkS")
		)
		(fp_line
			(start -0.7874 -0.4064)
			(end 0.7874 -0.4064)
			(stroke
				(width 0.1524)
				(type default)
			)
			(layer "F.SilkS")
		)
		(fp_line
			(start 0.7874 -0.4064)
			(end 0.7874 0.4064)
			(stroke
				(width 0.1524)
				(type default)
			)
			(layer "F.SilkS")
		)
		(fp_line
			(start -0.67945 0.3048)
			(end -0.67945 -0.305054)
			(stroke
				(width 0.1)
				(type default)
			)
			(layer "F.Fab")
		)
		(fp_line
			(start -0.12065 0.3048)
			(end -0.67945 0.3048)
			(stroke
				(width 0.1)
				(type default)
			)
			(layer "F.Fab")
		)
		(fp_line
			(start 0.120396 0.3048)
			(end 0.120396 0.2794)
			(stroke
				(width 0.1)
				(type default)
			)
			(layer "F.Fab")
		)
		(fp_line
			(start 0.67945 0.3048)
			(end 0.120396 0.3048)
			(stroke
				(width 0.1)
				(type default)
			)
			(layer "F.Fab")
		)
		(fp_line
			(start -0.12065 0.2794)
			(end -0.12065 0.3048)
			(stroke
				(width 0.1)
				(type default)
			)
			(layer "F.Fab")
		)
		(fp_line
			(start 0.120396 0.2794)
			(end -0.12065 0.2794)
			(stroke
				(width 0.1)
				(type default)
			)
			(layer "F.Fab")
		)
		(fp_line
			(start -0.12065 -0.2794)
			(end 0.12065 -0.2794)
			(stroke
				(width 0.1)
				(type default)
			)
			(layer "F.Fab")
		)
		(fp_line
			(start 0.12065 -0.2794)
			(end 0.12065 -0.3048)
			(stroke
				(width 0.1)
				(type default)
			)
			(layer "F.Fab")
		)
		(fp_line
			(start 0.12065 -0.3048)
			(end 0.67945 -0.3048)
			(stroke
				(width 0.1)
				(type default)
			)
			(layer "F.Fab")
		)
		(fp_line
			(start 0.67945 -0.3048)
			(end 0.67945 0.3048)
			(stroke
				(width 0.1)
				(type default)
			)
			(layer "F.Fab")
		)
		(fp_line
			(start -0.67945 -0.305054)
			(end -0.12065 -0.305054)
			(stroke
				(width 0.1)
				(type default)
			)
			(layer "F.Fab")
		)
		(fp_line
			(start -0.12065 -0.305054)
			(end -0.12065 -0.2794)
			(stroke
				(width 0.1)
				(type default)
			)
			(layer "F.Fab")
		)
		(pad "1" smd rect
			(at -0.40005 0 90)
			(size 0.4572 0.508)
			(layers "F.Cu" "F.Mask" "F.Paste")
			(net "P12V_OCP_SENSE_2")
		)
		(pad "2" smd rect
			(at 0.40005 0 90)
			(size 0.4572 0.508)
			(layers "F.Cu" "F.Mask" "F.Paste")
			(net "P12V_OCP_V3_2_ISENSE_MAM_MAM")
		)
	)
)
